(kicad_pcb
	(version 20221018)
	(generator pcbnew)
	(general
    (thickness 1.586)
  )
	(paper "A4")
	(title_block
    (date "2024-03-26")
    (rev "1.1.3")
		(comment 9 "footprints 19-24 of 146")
	)
	(layers
    (0 "F.Cu" signal)
    (1 "In1.Cu" power)
    (2 "In2.Cu" power)
    (31 "B.Cu" signal)
    (32 "B.Adhes" user "B.Adhesive")
    (33 "F.Adhes" user "F.Adhesive")
    (34 "B.Paste" user)
    (35 "F.Paste" user)
    (36 "B.SilkS" user "B.Silkscreen")
    (37 "F.SilkS" user "F.Silkscreen")
    (38 "B.Mask" user)
    (39 "F.Mask" user)
    (40 "Dwgs.User" user "User.Drawings")
    (41 "Cmts.User" user "User.Comments")
    (42 "Eco1.User" user "User.Eco1")
    (43 "Eco2.User" user "User.Eco2")
    (44 "Edge.Cuts" user)
    (45 "Margin" user)
    (46 "B.CrtYd" user "B.Courtyard")
    (47 "F.CrtYd" user "F.Courtyard")
    (48 "B.Fab" user)
    (49 "F.Fab" user)
  )
	(footprint "scalenode-cm4-baseboard-footprints:antmicro-logo"
		(layer "F.Cu")
    (at 97.420173 79.269924)
    (property "Author" "Antmicro")
    (property "License" "Apache-2.0")
    (property "MPN" "")
    (property "Manufacturer" "")
    (property "Sheetfile" "scalenode-cm4-baseboard.kicad_sch")
    (property "Sheetname" "")
    (attr through_hole exclude_from_pos_files)
    (fp_text reference "N1" (at -7.701 -10.301) (layer "F.SilkS") hide
        (effects (font (size 0.7 0.7) (thickness 0.15)) (justify left bottom))
    )
    (fp_text value "antmicro_logo" (at -5.3 10.099) (layer "F.SilkS") hide
        (effects (font (size 0.7 0.7) (thickness 0.15)) (justify left bottom))
    )
  )
	(footprint "scalenode-cm4-baseboard-footprints:SOIC127P1594X685-24N" (layer "F.Cu")
    (at 105.187 66.818 180)
    (descr "PS-2473.001-A")
    (tags "Inductor")
    (property "Author" "Antmicro")
    (property "Description" "Common Mode Chokes / Filters 1000Base-T SMD PoE+ 350uH .3Ohms 1-Port")
    (property "License" "Apache-2.0")
    (property "MPN" "H6096NL")
    (property "Manufacturer" "Pulse Electronics")
    (property "Sheetfile" "poe.kicad_sch")
    (property "Sheetname" "PoE")
    (property "ki_description" "Common Mode Chokes / Filters 1000Base-T SMD PoE+ 350uH .3Ohms 1-Port")
    (attr smd)
    (fp_text reference "L3" (at 5.397 -10.182 180) (layer "F.SilkS")
        (effects (font (size 0.7 0.7) (thickness 0.15)) (justify left bottom))
    )
    (fp_text value "H6096NL" (at 0.237 -12.082 180) (layer "F.SilkS") hide
        (effects (font (size 0.7 0.7) (thickness 0.15)) (justify left bottom))
    )
    (fp_text user "License: Apache-2.0" (at -8.75 13.854 180) (layer "F.Fab") hide
        (effects (font (size 0.7 0.7) (thickness 0.15)) (justify left bottom))
    )
    (fp_text user "${REFERENCE}" (at -8.75 11.454 180) (layer "F.Fab") hide
        (effects (font (size 0.7 0.7) (thickness 0.15)) (justify left bottom))
    )
    (fp_text user "Author: Antmicro" (at -8.75 12.653 180) (layer "F.Fab") hide
        (effects (font (size 0.7 0.7) (thickness 0.15)) (justify left bottom))
    )
    (fp_line (start -8.5 -7.76) (end -6.101 -7.76)
      (stroke (width 0.15) (type solid)) (layer "F.SilkS"))
    (fp_line (start -5.75 -9.08) (end 5.749 -9.08)
      (stroke (width 0.15) (type solid)) (layer "F.SilkS"))
    (fp_line (start -5.75 9.079) (end -5.75 -9.08)
      (stroke (width 0.15) (type solid)) (layer "F.SilkS"))
    (fp_line (start 5.749 -9.08) (end 5.749 9.079)
      (stroke (width 0.15) (type solid)) (layer "F.SilkS"))
    (fp_line (start 5.749 9.079) (end -5.75 9.079)
      (stroke (width 0.15) (type solid)) (layer "F.SilkS"))
    (fp_circle (center -9.017 -6.986) (end -8.967 -6.986)
      (stroke (width 0.15) (type solid)) (fill solid) (layer "F.SilkS"))
    (fp_line (start -8.75 -9.47) (end 8.74 -9.47)
      (stroke (width 0.05) (type solid)) (layer "F.CrtYd"))
    (fp_line (start -8.75 9.45) (end -8.75 -9.47)
      (stroke (width 0.05) (type solid)) (layer "F.CrtYd"))
    (fp_line (start 8.74 -9.47) (end 8.74 9.45)
      (stroke (width 0.05) (type solid)) (layer "F.CrtYd"))
    (fp_line (start 8.74 9.45) (end -8.75 9.45)
      (stroke (width 0.05) (type solid)) (layer "F.CrtYd"))
    (fp_line (start -6.101 -9.08) (end 6.099 -9.08)
      (stroke (width 0.15) (type solid)) (layer "F.Fab"))
    (fp_line (start -6.101 -7.811) (end -4.83 -9.08)
      (stroke (width 0.15) (type solid)) (layer "F.Fab"))
    (fp_line (start -6.101 9.079) (end -6.101 -9.08)
      (stroke (width 0.15) (type solid)) (layer "F.Fab"))
    (fp_line (start 6.099 -9.08) (end 6.099 9.079)
      (stroke (width 0.15) (type solid)) (layer "F.Fab"))
    (fp_line (start 6.099 9.079) (end -6.101 9.079)
      (stroke (width 0.15) (type solid)) (layer "F.Fab"))
    (pad "1" smd rect (at -7.3 -6.986 270) (size 0.85 2.4) (layers "F.Cu" "F.Paste" "F.Mask")
      (net 222 "Net-(L3-TCT1)") (pinfunction "TCT1") (pintype "passive"))
    (pad "2" smd rect (at -7.3 -5.715 270) (size 0.85 2.4) (layers "F.Cu" "F.Paste" "F.Mask")
      (net 87 "TRD0_P") (pinfunction "TD1+") (pintype "passive"))
    (pad "3" smd rect (at -7.3 -4.446 270) (size 0.85 2.4) (layers "F.Cu" "F.Paste" "F.Mask")
      (net 89 "TRD0_N") (pinfunction "TD1-") (pintype "passive"))
    (pad "4" smd rect (at -7.3 -3.176 270) (size 0.85 2.4) (layers "F.Cu" "F.Paste" "F.Mask")
      (net 223 "Net-(L3-TCT2)") (pinfunction "TCT2") (pintype "passive"))
    (pad "5" smd rect (at -7.3 -1.905 270) (size 0.85 2.4) (layers "F.Cu" "F.Paste" "F.Mask")
      (net 93 "TRD1_P") (pinfunction "TD2+") (pintype "passive"))
    (pad "6" smd rect (at -7.3 -0.635 270) (size 0.85 2.4) (layers "F.Cu" "F.Paste" "F.Mask")
      (net 91 "TRD1_N") (pinfunction "TD2-") (pintype "passive"))
    (pad "7" smd rect (at -7.3 0.633 270) (size 0.85 2.4) (layers "F.Cu" "F.Paste" "F.Mask")
      (net 224 "Net-(L3-TCT3)") (pinfunction "TCT3") (pintype "passive"))
    (pad "8" smd rect (at -7.3 1.904 270) (size 0.85 2.4) (layers "F.Cu" "F.Paste" "F.Mask")
      (net 88 "TRD2_P") (pinfunction "TD3+") (pintype "passive"))
    (pad "9" smd rect (at -7.3 3.173 270) (size 0.85 2.4) (layers "F.Cu" "F.Paste" "F.Mask")
      (net 90 "TRD2_N") (pinfunction "TD3-") (pintype "passive"))
    (pad "10" smd rect (at -7.3 4.445 270) (size 0.85 2.4) (layers "F.Cu" "F.Paste" "F.Mask")
      (net 228 "Net-(L3-TCT4)") (pinfunction "TCT4") (pintype "passive"))
    (pad "11" smd rect (at -7.3 5.714 270) (size 0.85 2.4) (layers "F.Cu" "F.Paste" "F.Mask")
      (net 94 "TRD3_P") (pinfunction "TD4+") (pintype "passive"))
    (pad "12" smd rect (at -7.3 6.985 270) (size 0.85 2.4) (layers "F.Cu" "F.Paste" "F.Mask")
      (net 92 "TRD3_N") (pinfunction "TD4-") (pintype "passive"))
    (pad "13" smd rect (at 7.299 6.985 270) (size 0.85 2.4) (layers "F.Cu" "F.Paste" "F.Mask")
      (net 160 "/PoE/T_ETH_D3_N") (pinfunction "MX4-") (pintype "passive"))
    (pad "14" smd rect (at 7.299 5.714 270) (size 0.85 2.4) (layers "F.Cu" "F.Paste" "F.Mask")
      (net 159 "/PoE/T_ETH_D3_P") (pinfunction "MX4+") (pintype "passive"))
    (pad "15" smd rect (at 7.299 4.445 270) (size 0.85 2.4) (layers "F.Cu" "F.Paste" "F.Mask")
      (net 20 "/PoE/PAIR78") (pinfunction "MCT4") (pintype "passive"))
    (pad "16" smd rect (at 7.299 3.173 270) (size 0.85 2.4) (layers "F.Cu" "F.Paste" "F.Mask")
      (net 157 "/PoE/T_ETH_D2_N") (pinfunction "MX3-") (pintype "passive"))
    (pad "17" smd rect (at 7.299 1.904 270) (size 0.85 2.4) (layers "F.Cu" "F.Paste" "F.Mask")
      (net 156 "/PoE/T_ETH_D2_P") (pinfunction "MX3+") (pintype "passive"))
    (pad "18" smd rect (at 7.299 0.633 270) (size 0.85 2.4) (layers "F.Cu" "F.Paste" "F.Mask")
      (net 3 "/PoE/PAIR45") (pinfunction "MCT3") (pintype "passive"))
    (pad "19" smd rect (at 7.299 -0.635 270) (size 0.85 2.4) (layers "F.Cu" "F.Paste" "F.Mask")
      (net 158 "/PoE/T_ETH_D1_N") (pinfunction "MX2-") (pintype "passive"))
    (pad "20" smd rect (at 7.299 -1.905 270) (size 0.85 2.4) (layers "F.Cu" "F.Paste" "F.Mask")
      (net 155 "/PoE/T_ETH_D1_P") (pinfunction "MX2+") (pintype "passive"))
    (pad "21" smd rect (at 7.299 -3.176 270) (size 0.85 2.4) (layers "F.Cu" "F.Paste" "F.Mask")
      (net 2 "/PoE/PAIR36") (pinfunction "MCT2") (pintype "passive"))
    (pad "22" smd rect (at 7.299 -4.446 270) (size 0.85 2.4) (layers "F.Cu" "F.Paste" "F.Mask")
      (net 154 "/PoE/T_ETH_D0_N") (pinfunction "MX1-") (pintype "passive"))
    (pad "23" smd rect (at 7.299 -5.715 270) (size 0.85 2.4) (layers "F.Cu" "F.Paste" "F.Mask")
      (net 153 "/PoE/T_ETH_D0_P") (pinfunction "MX1+") (pintype "passive"))
    (pad "24" smd rect (at 7.299 -6.986 270) (size 0.85 2.4) (layers "F.Cu" "F.Paste" "F.Mask")
      (net 1 "/PoE/PAIR12") (pinfunction "MCT1") (pintype "passive"))
  )
	(footprint "scalenode-cm4-baseboard-footprints:DFN-12-1EP_3x3mm" (layer "F.Cu")
    (at 165.19956 72.02372 180)
    (descr "http://www.ftdichip.com/Support/Documents/TechnicalNotes/TN_166%20FTDI%20Example%20IC%20PCB%20Footprints.pdf")
    (property "Author" "Antmicro")
    (property "License" "Apache-2.0")
    (property "MPN" "FT234XD-R")
    (property "Manufacturer" "FTDI Chip")
    (property "Sheetfile" "interfaces.kicad_sch")
    (property "Sheetname" "Interfaces")
    (property "ki_description" "USB to serial UART interface")
    (property "ki_keywords" "USB serial UART interface")
    (attr smd)
    (fp_text reference "U6" (at 2.19956 -1.47628 90) (layer "F.SilkS")
        (effects (font (size 0.7 0.7) (thickness 0.15)) (justify left bottom))
    )
    (fp_text value "FT234XD-R" (at 0 3.1) (layer "F.Fab")
        (effects (font (size 0.7 0.7) (thickness 0.15)) (justify right bottom))
    )
    (fp_text user "${REFERENCE}" (at -1.75 6.299) (layer "F.Fab") hide
        (effects (font (size 0.7 0.7) (thickness 0.15)) (justify right bottom))
    )
    (fp_text user "Author: Antmicro" (at -1.75 7.499) (layer "F.Fab") hide
        (effects (font (size 0.7 0.7) (thickness 0.15)) (justify right bottom))
    )
    (fp_text user "License: Apache-2.0" (at -1.75 8.699) (layer "F.Fab") hide
        (effects (font (size 0.7 0.7) (thickness 0.15)) (justify right bottom))
    )
    (fp_line (start -1.601 1.6) (end -1.601 1.396)
      (stroke (width 0.15) (type solid)) (layer "F.SilkS"))
    (fp_line (start -1.601 1.6) (end -1.397 1.6)
      (stroke (width 0.15) (type solid)) (layer "F.SilkS"))
    (fp_line (start -1.6 -1.5) (end -1.5 -1.6)
      (stroke (width 0.15) (type solid)) (layer "F.SilkS"))
    (fp_line (start -1.6 -1.4) (end -1.8 -1.4)
      (stroke (width 0.15) (type solid)) (layer "F.SilkS"))
    (fp_line (start -1.6 -1.4) (end -1.6 -1.5)
      (stroke (width 0.15) (type solid)) (layer "F.SilkS"))
    (fp_line (start -1.5 -1.6) (end -1.396 -1.6)
      (stroke (width 0.15) (type solid)) (layer "F.SilkS"))
    (fp_line (start 1.6 -1.601) (end 1.396 -1.601)
      (stroke (width 0.15) (type solid)) (layer "F.SilkS"))
    (fp_line (start 1.6 -1.601) (end 1.6 -1.397)
      (stroke (width 0.15) (type solid)) (layer "F.SilkS"))
    (fp_line (start 1.6 1.6) (end 1.396 1.6)
      (stroke (width 0.15) (type solid)) (layer "F.SilkS"))
    (fp_line (start 1.6 1.6) (end 1.6 1.396)
      (stroke (width 0.15) (type solid)) (layer "F.SilkS"))
    (fp_circle (center -1.8 -1.65) (end -1.8 -1.6)
      (stroke (width 0.15) (type solid)) (fill solid) (layer "F.SilkS"))
    (fp_rect (start -2 -1.79) (end 1.999 1.789)
      (stroke (width 0.05) (type solid)) (fill none) (layer "F.CrtYd"))
    (fp_line (start -1.5 -1.2) (end -1.5 1.499)
      (stroke (width 0.15) (type solid)) (layer "F.Fab"))
    (fp_line (start -1.2 -1.5) (end -1.5 -1.2)
      (stroke (width 0.15) (type solid)) (layer "F.Fab"))
    (fp_line (start -1.2 -1.5) (end 1.499 -1.5)
      (stroke (width 0.15) (type solid)) (layer "F.Fab"))
    (fp_line (start 1.499 -1.5) (end 1.499 1.499)
      (stroke (width 0.15) (type solid)) (layer "F.Fab"))
    (fp_line (start 1.499 1.499) (end -1.5 1.499)
      (stroke (width 0.15) (type solid)) (layer "F.Fab"))
    (pad "1" smd rect (at -1.551 -1.125 90) (size 0.25 0.65) (layers "F.Cu" "F.Paste" "F.Mask")
      (net 266 "Net-(U6-USBDM)") (pinfunction "USBDM") (pintype "bidirectional"))
    (pad "2" smd rect (at -1.551 -0.677 90) (size 0.25 0.65) (layers "F.Cu" "F.Paste" "F.Mask")
      (net 23 "Net-(U6-3.3VOUT)") (pinfunction "~{RESET}") (pintype "input"))
    (pad "3" smd rect (at -1.551 -0.227 90) (size 0.25 0.65) (layers "F.Cu" "F.Paste" "F.Mask")
      (net 23 "Net-(U6-3.3VOUT)") (pinfunction "3.3VOUT") (pintype "power_out"))
    (pad "4" smd rect (at -1.551 0.225 90) (size 0.25 0.65) (layers "F.Cu" "F.Paste" "F.Mask")
      (net 27 "/Interfaces/VBus_Slave") (pinfunction "VCC") (pintype "power_in"))
    (pad "5" smd rect (at -1.551 0.675 90) (size 0.25 0.65) (layers "F.Cu" "F.Paste" "F.Mask")
      (net 11 "GND") (pinfunction "GND") (pintype "passive"))
    (pad "6" smd rect (at -1.551 1.124 90) (size 0.25 0.65) (layers "F.Cu" "F.Paste" "F.Mask")
      (net 274 "unconnected-(U6-CBUS0-Pad6)") (pinfunction "CBUS0") (pintype "bidirectional+no_connect"))
    (pad "7" smd rect (at 1.55 1.124 90) (size 0.25 0.65) (layers "F.Cu" "F.Paste" "F.Mask")
      (net 268 "Net-(U6-TXD)") (pinfunction "TXD") (pintype "output"))
    (pad "8" smd rect (at 1.55 0.675 90) (size 0.25 0.65) (layers "F.Cu" "F.Paste" "F.Mask")
      (net 275 "unconnected-(U6-~{RTS}-Pad8)") (pinfunction "~{RTS}") (pintype "output+no_connect"))
    (pad "9" smd rect (at 1.55 0.225 90) (size 0.25 0.65) (layers "F.Cu" "F.Paste" "F.Mask")
      (net 23 "Net-(U6-3.3VOUT)") (pinfunction "VCCIO") (pintype "power_in"))
    (pad "10" smd rect (at 1.55 -0.227 90) (size 0.25 0.65) (layers "F.Cu" "F.Paste" "F.Mask")
      (net 265 "Net-(U6-RXD)") (pinfunction "RXD") (pintype "input"))
    (pad "11" smd rect (at 1.55 -0.677 90) (size 0.25 0.65) (layers "F.Cu" "F.Paste" "F.Mask")
      (net 276 "unconnected-(U6-~{CTS}-Pad11)") (pinfunction "~{CTS}") (pintype "input+no_connect"))
    (pad "12" smd rect (at 1.55 -1.125 90) (size 0.25 0.65) (layers "F.Cu" "F.Paste" "F.Mask")
      (net 267 "Net-(U6-USBDP)") (pinfunction "USBDP") (pintype "bidirectional"))
    (pad "13" smd rect (at 0 0 90) (size 2.5 1.7) (layers "F.Cu" "F.Paste" "F.Mask")
      (net 11 "GND") (pinfunction "GND") (pintype "power_in"))
  )
	(footprint "scalenode-cm4-baseboard-footprints:C_0402_1005Metric" (layer "F.Cu")
    (at 168.6414 70.1746 180)
    (descr "Capacitor SMD 0402")
    (tags "capacitor SMD 0402")
    (property "Author" "Antmicro")
    (property "Dielectric" "X5R")
    (property "License" "Apache-2.0")
    (property "MPN" "GRM155R61H104KE14D")
    (property "Manufacturer" "Murata")
    (property "Sheetfile" "interfaces.kicad_sch")
    (property "Sheetname" "Interfaces")
    (property "Val" "100n")
    (property "Voltage" "50V")
    (property "ki_description" " ")
    (attr smd)
    (fp_text reference "C54" (at -3.0586 -0.3254) (layer "F.SilkS")
        (effects (font (size 0.7 0.7) (thickness 0.15)) (justify right bottom))
    )
    (fp_text value "C_100n_0402" (at 0 1.4) (layer "F.Fab")
        (effects (font (size 0.7 0.7) (thickness 0.15)) (justify right bottom))
    )
    (fp_text user "Author: Antmicro" (at -0.932 4.17) (layer "F.Fab") hide
        (effects (font (size 0.7 0.7) (thickness 0.15)) (justify right bottom))
    )
    (fp_text user "License: Apache-2.0" (at -0.932 5.17) (layer "F.Fab") hide
        (effects (font (size 0.7 0.7) (thickness 0.15)) (justify right bottom))
    )
    (fp_text user "${REFERENCE}" (at -0.932 3.168) (layer "F.Fab") hide
        (effects (font (size 0.7 0.7) (thickness 0.15)) (justify right bottom))
    )
    (fp_rect (start -0.94 -0.47) (end 0.94 0.47)
      (stroke (width 0.05) (type solid)) (fill none) (layer "F.CrtYd"))
    (fp_rect (start -0.499 -0.249) (end 0.499 0.249)
      (stroke (width 0.15) (type solid)) (fill none) (layer "F.Fab"))
    (pad "1" smd roundrect (at -0.484 0 180) (size 0.59 0.64) (layers "F.Cu" "F.Paste" "F.Mask") (roundrect_rratio 0.25)
      (net 11 "GND") (pintype "passive"))
    (pad "2" smd roundrect (at 0.484 0 180) (size 0.59 0.64) (layers "F.Cu" "F.Paste" "F.Mask") (roundrect_rratio 0.25)
      (net 27 "/Interfaces/VBus_Slave") (pintype "passive"))
  )
	(footprint "scalenode-cm4-baseboard-footprints:C_0402_1005Metric" (layer "F.Cu")
    (at 168.6438 71.1906 180)
    (descr "Capacitor SMD 0402")
    (tags "capacitor SMD 0402")
    (property "Author" "Antmicro")
    (property "Dielectric" "")
    (property "License" "Apache-2.0")
    (property "MPN" "C1005X6S1A105K050BC")
    (property "Manufacturer" "TDK")
    (property "Sheetfile" "interfaces.kicad_sch")
    (property "Sheetname" "Interfaces")
    (property "Val" "1u")
    (property "Voltage" "")
    (property "ki_description" " ")
    (attr smd)
    (fp_text reference "C53" (at -3.0562 -0.3594) (layer "F.SilkS")
        (effects (font (size 0.7 0.7) (thickness 0.15)) (justify right bottom))
    )
    (fp_text value "C_1u_0402" (at 0 1.4) (layer "F.Fab")
        (effects (font (size 0.7 0.7) (thickness 0.15)) (justify right bottom))
    )
    (fp_text user "${REFERENCE}" (at -0.932 3.168) (layer "F.Fab") hide
        (effects (font (size 0.7 0.7) (thickness 0.15)) (justify right bottom))
    )
    (fp_text user "License: Apache-2.0" (at -0.932 5.17) (layer "F.Fab") hide
        (effects (font (size 0.7 0.7) (thickness 0.15)) (justify right bottom))
    )
    (fp_text user "Author: Antmicro" (at -0.932 4.17) (layer "F.Fab") hide
        (effects (font (size 0.7 0.7) (thickness 0.15)) (justify right bottom))
    )
    (fp_rect (start -0.94 -0.47) (end 0.94 0.47)
      (stroke (width 0.05) (type solid)) (fill none) (layer "F.CrtYd"))
    (fp_rect (start -0.499 -0.249) (end 0.499 0.249)
      (stroke (width 0.15) (type solid)) (fill none) (layer "F.Fab"))
    (pad "1" smd roundrect (at -0.484 0 180) (size 0.59 0.64) (layers "F.Cu" "F.Paste" "F.Mask") (roundrect_rratio 0.25)
      (net 11 "GND") (pintype "passive"))
    (pad "2" smd roundrect (at 0.484 0 180) (size 0.59 0.64) (layers "F.Cu" "F.Paste" "F.Mask") (roundrect_rratio 0.25)
      (net 27 "/Interfaces/VBus_Slave") (pintype "passive"))
  )
	(footprint "scalenode-cm4-baseboard-footprints:R_0402_1005Metric" (layer "F.Cu")
    (at 164.13456 74.33004 180)
    (descr "Resistor SMD 0402")
    (tags "resistor SMD 0402")
    (property "Author" "Antmicro")
    (property "License" "Apache-2.0")
    (property "MPN" "CR0402-FX-22R0GLF")
    (property "Manufacturer" "Bourns")
    (property "Sheetfile" "interfaces.kicad_sch")
    (property "Sheetname" "Interfaces")
    (property "Tolerance" "1%")
    (property "Val" "22R")
    (property "ki_description" "22R resistor in 0402 package with 1% tolerance")
    (attr smd)
    (fp_text reference "R59" (at 1.03456 -1.44496 180) (layer "F.SilkS")
        (effects (font (size 0.7 0.7) (thickness 0.15)) (justify left bottom))
    )
    (fp_text value "R_22R_0402" (at 0 1.4 180) (layer "F.Fab")
        (effects (font (size 0.7 0.7) (thickness 0.15)) (justify left bottom))
    )
    (fp_text user "Author: Antmicro" (at -0.95 4.169 180) (layer "F.Fab") hide
        (effects (font (size 0.7 0.7) (thickness 0.15)) (justify left bottom))
    )
    (fp_text user "${REFERENCE}" (at -0.95 3.168 180) (layer "F.Fab") hide
        (effects (font (size 0.7 0.7) (thickness 0.15)) (justify left bottom))
    )
    (fp_text user "License: Apache-2.0" (at -0.95 5.169 180) (layer "F.Fab") hide
        (effects (font (size 0.7 0.7) (thickness 0.15)) (justify left bottom))
    )
    (fp_rect (start -0.95 -0.48) (end 0.95 0.48)
      (stroke (width 0.05) (type solid)) (fill none) (layer "F.CrtYd"))
    (fp_rect (start -0.5 -0.25) (end 0.5 0.25)
      (stroke (width 0.15) (type solid)) (fill none) (layer "F.Fab"))
    (pad "1" smd roundrect (at -0.485 0 180) (size 0.59 0.64) (layers "F.Cu" "F.Paste" "F.Mask") (roundrect_rratio 0.25)
      (net 251 "/Interfaces/FTDI_USB_P") (pintype "passive"))
    (pad "2" smd roundrect (at 0.485 0 180) (size 0.59 0.64) (layers "F.Cu" "F.Paste" "F.Mask") (roundrect_rratio 0.25)
      (net 267 "Net-(U6-USBDP)") (pintype "passive"))
  )
)
